(kicad_pcb
	(version 20260206)
	(generator "pcbnew")
	(generator_version "10.0")
	(general
		(thickness 1.6)
		(legacy_teardrops no)
	)
	(paper "A4")
	(title_block
		(title "Wiwynn_Tioga_Pass_MB.brd")
		(comment 1 "Tioga Pass / footprints 1226-1231 of 4770")
	)
	(layers
		(0 "F.Cu" signal "TOP")
		(4 "In1.Cu" signal "L2GND")
		(6 "In2.Cu" signal "L3")
		(8 "In3.Cu" signal "L4GND")
		(10 "In4.Cu" signal "L5")
		(12 "In5.Cu" signal "L6GND")
		(14 "In6.Cu" signal "L7VCC")
		(16 "In7.Cu" signal "L8VCC")
		(18 "In8.Cu" signal "L9GND")
		(20 "In9.Cu" signal "L10")
		(22 "In10.Cu" signal "L11GND")
		(24 "In11.Cu" signal "L12")
		(26 "In12.Cu" signal "L13GND")
		(2 "B.Cu" signal "BOTTOM")
		(9 "F.Adhes" user "F.Adhesive")
		(11 "B.Adhes" user "B.Adhesive")
		(13 "F.Paste" user "Package Geometry/Pastemask Top")
		(15 "B.Paste" user "Package Geometry/Pastemask Bottom")
		(5 "F.SilkS" user "Ref Des/Silkscreen Top")
		(7 "B.SilkS" user "Ref Des/Silkscreen Bottom")
		(1 "F.Mask" user "Board Geometry/Soldermask Top")
		(3 "B.Mask" user "Board Geometry/Soldermask Bottom")
		(17 "Dwgs.User" user "User.Drawings")
		(19 "Cmts.User" user "User.Comments")
		(21 "Eco1.User" user "User.Eco1")
		(23 "Eco2.User" user "User.Eco2")
		(25 "Edge.Cuts" user "Board Geometry/Outline")
		(27 "Margin" user)
		(31 "F.CrtYd" user "Package Geometry/Place Bound Top")
		(29 "B.CrtYd" user "Package Geometry/Place Bound Bottom")
		(35 "F.Fab" user "Ref Des/Assembly Top")
		(33 "B.Fab" user "Ref Des/Assembly Bottom")
	)
	(footprint ""
		(layer "F.Cu")
		(at 24.230584 -95.827596)
		(property "Reference" "R1C21"
			(at 0 0 0)
			(layer "F.SilkS")
			(hide yes)
			(effects
				(font
					(size 1.27 1.27)
				)
			)
		)
		(property "Value" ""
			(at 0 0 0)
			(layer "F.Fab")
			(effects
				(font
					(size 1.27 1.27)
				)
			)
		)
		(duplicate_pad_numbers_are_jumpers no)
		(fp_rect
			(start -0.2794 0.9906)
			(end 0.2794 -0.1016)
			(stroke
				(width 0)
				(type default)
			)
			(fill no)
			(layer "F.CrtYd")
		)
		(fp_line
			(start -0.2794 -0.1016)
			(end -0.2794 0.9906)
			(stroke
				(width 0.1)
				(type default)
			)
			(layer "F.Fab")
		)
		(fp_line
			(start -0.2794 0.9906)
			(end 0.2794 0.9906)
			(stroke
				(width 0.1)
				(type default)
			)
			(layer "F.Fab")
		)
		(fp_line
			(start 0.2794 -0.1016)
			(end -0.2794 -0.1016)
			(stroke
				(width 0.1)
				(type default)
			)
			(layer "F.Fab")
		)
		(fp_line
			(start 0.2794 0.9906)
			(end 0.2794 -0.1016)
			(stroke
				(width 0.1)
				(type default)
			)
			(layer "F.Fab")
		)
		(pad "1" smd rect
			(at 0 0)
			(size 0.508 0.508)
			(layers "F.Cu" "F.Mask" "F.Paste")
			(net "VSENSE_PVSA_CPU1_P")
		)
		(pad "2" smd rect
			(at 0 0.889)
			(size 0.508 0.508)
			(layers "F.Cu" "F.Mask" "F.Paste")
			(net "VSENSE_PVSA_CPU1_BVSP")
		)
		(zone
			(layer "F.Cu")
			(hatch none 0.5)
			(connect_pads
				(clearance 0)
			)
			(min_thickness 0.25)
			(keepout
				(tracks allowed)
				(vias not_allowed)
				(pads allowed)
				(copperpour not_allowed)
				(footprints allowed)
			)
			(placement
				(enabled no)
				(sheetname "")
			)
			(fill
				(thermal_gap 0.5)
				(thermal_bridge_width 0.5)
				(island_removal_mode 0)
			)
			(polygon
				(pts
					(xy 23.976584 -95.192596) (xy 24.484584 -95.192596) (xy 24.484584 -95.573596) (xy 23.976584 -95.573596)
				)
			)
		)
		(zone
			(layer "F.Cu")
			(hatch none 0.5)
			(connect_pads
				(clearance 0)
			)
			(min_thickness 0.25)
			(keepout
				(tracks not_allowed)
				(vias allowed)
				(pads allowed)
				(copperpour not_allowed)
				(footprints allowed)
			)
			(placement
				(enabled no)
				(sheetname "")
			)
			(fill
				(thermal_gap 0.5)
				(thermal_bridge_width 0.5)
				(island_removal_mode 0)
			)
			(polygon
				(pts
					(xy 23.976584 -95.192596) (xy 24.484584 -95.192596) (xy 24.484584 -95.573596) (xy 23.976584 -95.573596)
				)
			)
		)
	)
	(footprint ""
		(layer "F.Cu")
		(at 28.194 -91.567 90)
		(property "Reference" "C1C24"
			(at 0 0 90)
			(layer "F.SilkS")
			(hide yes)
			(effects
				(font
					(size 1.27 1.27)
				)
			)
		)
		(property "Value" ""
			(at 0 0 90)
			(layer "F.Fab")
			(effects
				(font
					(size 1.27 1.27)
				)
			)
		)
		(duplicate_pad_numbers_are_jumpers no)
		(fp_rect
			(start -0.3048 0.9906)
			(end 0.3048 -0.1016)
			(stroke
				(width 0)
				(type default)
			)
			(fill no)
			(layer "F.CrtYd")
		)
		(fp_line
			(start 0.3048 -0.1016)
			(end -0.3048 -0.1016)
			(stroke
				(width 0.1)
				(type default)
			)
			(layer "F.Fab")
		)
		(fp_line
			(start -0.3048 -0.1016)
			(end -0.3048 0.9906)
			(stroke
				(width 0.1)
				(type default)
			)
			(layer "F.Fab")
		)
		(fp_line
			(start 0.3048 0.9906)
			(end 0.3048 -0.1016)
			(stroke
				(width 0.1)
				(type default)
			)
			(layer "F.Fab")
		)
		(fp_line
			(start -0.3048 0.9906)
			(end 0.3048 0.9906)
			(stroke
				(width 0.1)
				(type default)
			)
			(layer "F.Fab")
		)
		(pad "1" smd rect
			(at 0 0 90)
			(size 0.508 0.508)
			(layers "F.Cu" "F.Mask" "F.Paste")
			(net "VR_PVCCIN_CPU1_PH5_BOOT")
		)
		(pad "2" smd rect
			(at 0 0.889 90)
			(size 0.508 0.508)
			(layers "F.Cu" "F.Mask" "F.Paste")
			(net "VR_PVCCIN_CPU1_PH5_PHASE")
		)
		(zone
			(layer "F.Cu")
			(hatch none 0.5)
			(connect_pads
				(clearance 0)
			)
			(min_thickness 0.25)
			(keepout
				(tracks not_allowed)
				(vias allowed)
				(pads allowed)
				(copperpour not_allowed)
				(footprints allowed)
			)
			(placement
				(enabled no)
				(sheetname "")
			)
			(fill
				(thermal_gap 0.5)
				(thermal_bridge_width 0.5)
				(island_removal_mode 0)
			)
			(polygon
				(pts
					(xy 28.829 -91.313) (xy 28.829 -91.821) (xy 28.448 -91.821) (xy 28.448 -91.313)
				)
			)
		)
		(zone
			(layer "F.Cu")
			(hatch none 0.5)
			(connect_pads
				(clearance 0)
			)
			(min_thickness 0.25)
			(keepout
				(tracks allowed)
				(vias not_allowed)
				(pads allowed)
				(copperpour not_allowed)
				(footprints allowed)
			)
			(placement
				(enabled no)
				(sheetname "")
			)
			(fill
				(thermal_gap 0.5)
				(thermal_bridge_width 0.5)
				(island_removal_mode 0)
			)
			(polygon
				(pts
					(xy 28.829 -91.313) (xy 28.829 -91.821) (xy 28.448 -91.821) (xy 28.448 -91.313)
				)
			)
		)
	)
	(footprint ""
		(layer "F.Cu")
		(at 33.2105 -84.836 90)
		(property "Reference" "C1D13"
			(at 0 0 90)
			(layer "F.SilkS")
			(hide yes)
			(effects
				(font
					(size 1.27 1.27)
				)
			)
		)
		(property "Value" ""
			(at 0 0 90)
			(layer "F.Fab")
			(effects
				(font
					(size 1.27 1.27)
				)
			)
		)
		(duplicate_pad_numbers_are_jumpers no)
		(fp_rect
			(start 0.3048 0.9906)
			(end -0.3048 -0.1016)
			(stroke
				(width 0)
				(type default)
			)
			(fill no)
			(layer "F.CrtYd")
		)
		(fp_line
			(start 0.3048 -0.1016)
			(end -0.3048 -0.1016)
			(stroke
				(width 0.1)
				(type default)
			)
			(layer "F.Fab")
		)
		(fp_line
			(start -0.3048 -0.1016)
			(end -0.3048 0.9906)
			(stroke
				(width 0.1)
				(type default)
			)
			(layer "F.Fab")
		)
		(fp_line
			(start 0.3048 0.9906)
			(end 0.3048 -0.1016)
			(stroke
				(width 0.1)
				(type default)
			)
			(layer "F.Fab")
		)
		(fp_line
			(start -0.3048 0.9906)
			(end 0.3048 0.9906)
			(stroke
				(width 0.1)
				(type default)
			)
			(layer "F.Fab")
		)
		(pad "1" smd rect
			(at 0 0 90)
			(size 0.508 0.508)
			(layers "F.Cu" "F.Mask" "F.Paste")
			(net "VR_FET_SW_P12V_STBY_PVCCIN_CPU1")
		)
		(pad "2" smd rect
			(at 0 0.889 90)
			(size 0.508 0.508)
			(layers "F.Cu" "F.Mask" "F.Paste")
			(net "GND")
		)
		(zone
			(layer "F.Cu")
			(hatch none 0.5)
			(connect_pads
				(clearance 0)
			)
			(min_thickness 0.25)
			(keepout
				(tracks allowed)
				(vias not_allowed)
				(pads allowed)
				(copperpour not_allowed)
				(footprints allowed)
			)
			(placement
				(enabled no)
				(sheetname "")
			)
			(fill
				(thermal_gap 0.5)
				(thermal_bridge_width 0.5)
				(island_removal_mode 0)
			)
			(polygon
				(pts
					(xy 33.8455 -85.09) (xy 33.4645 -85.09) (xy 33.4645 -84.582) (xy 33.8455 -84.582)
				)
			)
		)
		(zone
			(layer "F.Cu")
			(hatch none 0.5)
			(connect_pads
				(clearance 0)
			)
			(min_thickness 0.25)
			(keepout
				(tracks not_allowed)
				(vias allowed)
				(pads allowed)
				(copperpour not_allowed)
				(footprints allowed)
			)
			(placement
				(enabled no)
				(sheetname "")
			)
			(fill
				(thermal_gap 0.5)
				(thermal_bridge_width 0.5)
				(island_removal_mode 0)
			)
			(polygon
				(pts
					(xy 33.8455 -85.09) (xy 33.4645 -85.09) (xy 33.4645 -84.582) (xy 33.8455 -84.582)
				)
			)
		)
	)
	(footprint ""
		(layer "F.Cu")
		(at 404.990554 -100.337112 180)
		(property "Reference" "C8C1"
			(at 0 0 180)
			(layer "F.SilkS")
			(hide yes)
			(effects
				(font
					(size 1.27 1.27)
				)
			)
		)
		(property "Value" ""
			(at 0 0 180)
			(layer "F.Fab")
			(effects
				(font
					(size 1.27 1.27)
				)
			)
		)
		(duplicate_pad_numbers_are_jumpers no)
		(fp_poly
			(pts
				(xy 0.3048 -0.1016) (xy 0.3048 0.9906) (xy -0.3048 0.9906) (xy -0.3048 -0.1016)
			)
			(stroke
				(width 0)
				(type default)
			)
			(fill no)
			(layer "F.CrtYd")
		)
		(fp_line
			(start 0.3048 0.9906)
			(end 0.3048 -0.1016)
			(stroke
				(width 0.1)
				(type default)
			)
			(layer "F.Fab")
		)
		(fp_line
			(start 0.3048 -0.1016)
			(end -0.3048 -0.1016)
			(stroke
				(width 0.1)
				(type default)
			)
			(layer "F.Fab")
		)
		(fp_line
			(start -0.3048 0.9906)
			(end 0.3048 0.9906)
			(stroke
				(width 0.1)
				(type default)
			)
			(layer "F.Fab")
		)
		(fp_line
			(start -0.3048 -0.1016)
			(end -0.3048 0.9906)
			(stroke
				(width 0.1)
				(type default)
			)
			(layer "F.Fab")
		)
		(pad "1" smd rect
			(at 0 0 180)
			(size 0.508 0.508)
			(layers "F.Cu" "F.Mask" "F.Paste")
			(net "XTAL_KR_25M_IN")
		)
		(pad "2" smd rect
			(at 0 0.889 180)
			(size 0.508 0.508)
			(layers "F.Cu" "F.Mask" "F.Paste")
			(net "GND")
		)
		(zone
			(layer "F.Cu")
			(hatch none 0.5)
			(connect_pads
				(clearance 0)
			)
			(min_thickness 0.25)
			(keepout
				(tracks not_allowed)
				(vias allowed)
				(pads allowed)
				(copperpour not_allowed)
				(footprints allowed)
			)
			(placement
				(enabled no)
				(sheetname "")
			)
			(fill
				(thermal_gap 0.5)
				(thermal_bridge_width 0.5)
				(island_removal_mode 0)
			)
			(polygon
				(pts
					(xy 405.244554 -100.972112) (xy 404.736554 -100.972112) (xy 404.736554 -100.591112) (xy 405.244554 -100.591112)
				)
			)
		)
		(zone
			(layer "F.Cu")
			(hatch none 0.5)
			(connect_pads
				(clearance 0)
			)
			(min_thickness 0.25)
			(keepout
				(tracks allowed)
				(vias not_allowed)
				(pads allowed)
				(copperpour not_allowed)
				(footprints allowed)
			)
			(placement
				(enabled no)
				(sheetname "")
			)
			(fill
				(thermal_gap 0.5)
				(thermal_bridge_width 0.5)
				(island_removal_mode 0)
			)
			(polygon
				(pts
					(xy 405.244554 -100.591112) (xy 404.736554 -100.591112) (xy 404.736554 -100.972112) (xy 405.244554 -100.972112)
				)
			)
		)
	)
	(footprint ""
		(layer "F.Cu")
		(at 334.137 -24.13 90)
		(property "Reference" "R7F12"
			(at 0 0 90)
			(layer "F.SilkS")
			(hide yes)
			(effects
				(font
					(size 1.27 1.27)
				)
			)
		)
		(property "Value" ""
			(at 0 0 90)
			(layer "F.Fab")
			(effects
				(font
					(size 1.27 1.27)
				)
			)
		)
		(duplicate_pad_numbers_are_jumpers no)
		(fp_rect
			(start 0.2794 0.9906)
			(end -0.2794 -0.1016)
			(stroke
				(width 0)
				(type default)
			)
			(fill no)
			(layer "F.CrtYd")
		)
		(fp_line
			(start 0.2794 -0.1016)
			(end -0.2794 -0.1016)
			(stroke
				(width 0.1)
				(type default)
			)
			(layer "F.Fab")
		)
		(fp_line
			(start -0.2794 -0.1016)
			(end -0.2794 0.9906)
			(stroke
				(width 0.1)
				(type default)
			)
			(layer "F.Fab")
		)
		(fp_line
			(start 0.2794 0.9906)
			(end 0.2794 -0.1016)
			(stroke
				(width 0.1)
				(type default)
			)
			(layer "F.Fab")
		)
		(fp_line
			(start -0.2794 0.9906)
			(end 0.2794 0.9906)
			(stroke
				(width 0.1)
				(type default)
			)
			(layer "F.Fab")
		)
		(pad "1" smd rect
			(at 0 0 90)
			(size 0.508 0.508)
			(layers "F.Cu" "F.Mask" "F.Paste")
			(net "PVPP_ABC")
		)
		(pad "2" smd rect
			(at 0 0.889 90)
			(size 0.508 0.508)
			(layers "F.Cu" "F.Mask" "F.Paste")
			(net "VSENSE_PVPP_ABC")
		)
		(zone
			(layer "F.Cu")
			(hatch none 0.5)
			(connect_pads
				(clearance 0)
			)
			(min_thickness 0.25)
			(keepout
				(tracks not_allowed)
				(vias allowed)
				(pads allowed)
				(copperpour not_allowed)
				(footprints allowed)
			)
			(placement
				(enabled no)
				(sheetname "")
			)
			(fill
				(thermal_gap 0.5)
				(thermal_bridge_width 0.5)
				(island_removal_mode 0)
			)
			(polygon
				(pts
					(xy 334.772 -24.384) (xy 334.391 -24.384) (xy 334.391 -23.876) (xy 334.772 -23.876)
				)
			)
		)
		(zone
			(layer "F.Cu")
			(hatch none 0.5)
			(connect_pads
				(clearance 0)
			)
			(min_thickness 0.25)
			(keepout
				(tracks allowed)
				(vias not_allowed)
				(pads allowed)
				(copperpour not_allowed)
				(footprints allowed)
			)
			(placement
				(enabled no)
				(sheetname "")
			)
			(fill
				(thermal_gap 0.5)
				(thermal_bridge_width 0.5)
				(island_removal_mode 0)
			)
			(polygon
				(pts
					(xy 334.772 -24.384) (xy 334.391 -24.384) (xy 334.391 -23.876) (xy 334.772 -23.876)
				)
			)
		)
	)
	(footprint ""
		(layer "F.Cu")
		(at 29.464 -12.4841 180)
		(property "Reference" "R1G3"
			(at 0 0 180)
			(layer "F.SilkS")
			(hide yes)
			(effects
				(font
					(size 1.27 1.27)
				)
			)
		)
		(property "Value" ""
			(at 0 0 180)
			(layer "F.Fab")
			(effects
				(font
					(size 1.27 1.27)
				)
			)
		)
		(duplicate_pad_numbers_are_jumpers no)
		(fp_poly
			(pts
				(xy -0.2794 -0.1016) (xy 0.2794 -0.1016) (xy 0.2794 0.9906) (xy -0.2794 0.9906)
			)
			(stroke
				(width 0)
				(type default)
			)
			(fill no)
			(layer "F.CrtYd")
		)
		(fp_line
			(start 0.2794 0.9906)
			(end 0.2794 -0.1016)
			(stroke
				(width 0.1)
				(type default)
			)
			(layer "F.Fab")
		)
		(fp_line
			(start 0.2794 -0.1016)
			(end -0.2794 -0.1016)
			(stroke
				(width 0.1)
				(type default)
			)
			(layer "F.Fab")
		)
		(fp_line
			(start -0.2794 0.9906)
			(end 0.2794 0.9906)
			(stroke
				(width 0.1)
				(type default)
			)
			(layer "F.Fab")
		)
		(fp_line
			(start -0.2794 -0.1016)
			(end -0.2794 0.9906)
			(stroke
				(width 0.1)
				(type default)
			)
			(layer "F.Fab")
		)
		(pad "1" smd rect
			(at 0 0 180)
			(size 0.508 0.508)
			(layers "F.Cu" "F.Mask" "F.Paste")
			(net "M_H_VREF")
		)
		(pad "2" smd rect
			(at 0 0.889 180)
			(size 0.508 0.508)
			(layers "F.Cu" "F.Mask" "F.Paste")
			(net "GND")
		)
		(zone
			(layer "F.Cu")
			(hatch none 0.5)
			(connect_pads
				(clearance 0)
			)
			(min_thickness 0.25)
			(keepout
				(tracks not_allowed)
				(vias allowed)
				(pads allowed)
				(copperpour not_allowed)
				(footprints allowed)
			)
			(placement
				(enabled no)
				(sheetname "")
			)
			(fill
				(thermal_gap 0.5)
				(thermal_bridge_width 0.5)
				(island_removal_mode 0)
			)
			(polygon
				(pts
					(xy 29.718 -13.1191) (xy 29.21 -13.1191) (xy 29.21 -12.7381) (xy 29.718 -12.7381)
				)
			)
		)
		(zone
			(layer "F.Cu")
			(hatch none 0.5)
			(connect_pads
				(clearance 0)
			)
			(min_thickness 0.25)
			(keepout
				(tracks allowed)
				(vias not_allowed)
				(pads allowed)
				(copperpour not_allowed)
				(footprints allowed)
			)
			(placement
				(enabled no)
				(sheetname "")
			)
			(fill
				(thermal_gap 0.5)
				(thermal_bridge_width 0.5)
				(island_removal_mode 0)
			)
			(polygon
				(pts
					(xy 29.718 -12.7381) (xy 29.21 -12.7381) (xy 29.21 -13.1191) (xy 29.718 -13.1191)
				)
			)
		)
	)
)
